# TIMECARD (Time Appliance Project (Time Card)) — schematic netlist excerpt (pin names and nets, part order shuffled) for the footprints in the layout excerpt that follows; sources: Cadence DE-HDL packaged netlist, KiCad conversion of R4006-B0001-02_R01.brd

U41  ISL80101IRAJZ_DFN10  pkg DFN11_118_P0197_TR057X071  page 33
  VOUT_1  = XP3R3V_FT4232
  VOUT_2  = XP3R3V_FT4232
  \sense/adj\  = UNNAMED_525_ISL80101IRAJZDFN10_
  PG  = XP3R3V_FT_PG
  GND  = SG
  SS  = UNNAMED_525_CAPACITOR_I18_1
  ENABLE  = UNNAMED_525_CAPACITOR_I14_1
  NC  = NC
  VIN_1  = UNNAMED_525_CAPACITOR_I16_1
  VIN_2  = UNNAMED_525_CAPACITOR_I16_1
  THRM_PAD  = SG

TP18  TP_PIONT  pkg TP010CT020B030_PTH  page 25 : \1\ = R_BNO080_BOOT_N

(kicad_pcb
	(version 20260206)
	(generator "pcbnew")
	(generator_version "10.0")
	(general
		(thickness 1.6)
		(legacy_teardrops no)
	)
	(paper "A4")
	(title_block
		(title "timecard-production-celestica-r4006 — R4006-B0001-02_R01.brd")
		(comment 1 "Time Appliance Project (Time Card) / footprints 300-301 of 1113")
	)
	(layers
		(0 "F.Cu" signal "TOP")
		(4 "In1.Cu" signal "L02_GND1")
		(6 "In2.Cu" signal "L03_SIG1")
		(8 "In3.Cu" signal "L04_GND2")
		(10 "In4.Cu" signal "L05_VCC1")
		(12 "In5.Cu" signal "L06_VCC2")
		(14 "In6.Cu" signal "L07_GND3")
		(16 "In7.Cu" signal "L08_SIG2")
		(18 "In8.Cu" signal "L09_GND4")
		(2 "B.Cu" signal "BOTTOM")
		(9 "F.Adhes" user "F.Adhesive")
		(11 "B.Adhes" user "B.Adhesive")
		(13 "F.Paste" user "Package Geometry/Pastemask Top")
		(15 "B.Paste" user "Package Geometry/Pastemask Bottom")
		(5 "F.SilkS" user "Ref Des/Silkscreen Top")
		(7 "B.SilkS" user "Ref Des/Silkscreen Bottom")
		(1 "F.Mask" user "Board Geometry/Soldermask Top")
		(3 "B.Mask" user "Board Geometry/Soldermask Bottom")
		(17 "Dwgs.User" user "User.Drawings")
		(19 "Cmts.User" user "User.Comments")
		(21 "Eco1.User" user "User.Eco1")
		(23 "Eco2.User" user "User.Eco2")
		(25 "Edge.Cuts" user "Board Geometry/Outline")
		(27 "Margin" user)
		(31 "F.CrtYd" user "Package Geometry/Place Bound Top")
		(29 "B.CrtYd" user "Package Geometry/Place Bound Bottom")
		(35 "F.Fab" user "Ref Des/Assembly Top")
		(33 "B.Fab" user "Ref Des/Assembly Bottom")
	)
	(footprint ""
		(layer "F.Cu")
		(at 42.672 -76.581)
		(property "Reference" "U41"
			(at -0.889 2.83337 0)
			(unlocked yes)
			(layer "F.SilkS")
			(effects
				(font
					(size 0.7874 0.5842)
					(thickness 0.1524)
				)
			)
		)
		(property "Value" ""
			(at 0 0 0)
			(layer "F.Fab")
			(effects
				(font
					(size 1.27 1.27)
				)
			)
		)
		(property "Device Type" "ISL80101IRAJZ_DFN10-G222-10136A"
			(at 0.276606 2.583688 0)
			(unlocked yes)
			(layer "F.Fab")
			(hide yes)
			(effects
				(font
					(size 0.7874 0.5842)
					(thickness 0.1524)
				)
			)
		)
		(property "User Part Number" "PARTNUM*"
			(at 0.276606 3.517646 0)
			(unlocked yes)
			(layer "Cmts.User")
			(hide yes)
			(effects
				(font
					(size 0.7874 0.5842)
					(thickness 0.1524)
				)
			)
		)
		(duplicate_pad_numbers_are_jumpers no)
		(fp_line
			(start -2.290318 -1.779016)
			(end 2.290318 -1.779016)
			(stroke
				(width 0.1)
				(type default)
			)
			(layer "F.SilkS")
		)
		(fp_line
			(start -2.290318 1.779016)
			(end -2.290318 -1.779016)
			(stroke
				(width 0.1)
				(type default)
			)
			(layer "F.SilkS")
		)
		(fp_line
			(start 2.290318 -1.779016)
			(end 2.290318 1.779016)
			(stroke
				(width 0.1)
				(type default)
			)
			(layer "F.SilkS")
		)
		(fp_line
			(start 2.290318 1.779016)
			(end -2.290318 1.779016)
			(stroke
				(width 0.1)
				(type default)
			)
			(layer "F.SilkS")
		)
		(fp_poly
			(pts
				(arc
					(start -2.553462 -1.023112)
					(mid -3.315462 -1.023112)
					(end -2.553462 -1.023112)
				)
			)
			(stroke
				(width 0)
				(type default)
			)
			(fill yes)
			(layer "F.SilkS")
		)
		(fp_poly
			(pts
				(xy -0.7239 -0.1016)
				(arc
					(start -0.7239 -0.6477)
					(mid -0.290295 -0.468095)
					(end -0.4699 -0.9017)
				)
				(xy 0.7239 -0.9017) (xy 0.7239 -0.1016)
			)
			(stroke
				(width 0)
				(type default)
			)
			(fill yes)
			(layer "F.Paste")
		)
		(fp_poly
			(pts
				(xy -0.7239 0.1016) (xy 0.7239 0.1016) (xy 0.7239 0.635)
				(arc
					(start 0.723646 0.635254)
					(mid 0.645086 0.463711)
					(end 0.4699 0.3937)
				)
				(arc
					(start 0.4699 0.3937)
					(mid 0.290295 0.468095)
					(end 0.2159 0.6477)
				)
				(arc
					(start 0.2159 0.6477)
					(mid 0.284118 0.820908)
					(end 0.45212 0.901192)
				)
				(xy 0.45212 0.9017) (xy -0.7239 0.9017)
			)
			(stroke
				(width 0)
				(type default)
			)
			(fill yes)
			(layer "F.Paste")
		)
		(fp_poly
			(pts
				(xy -2.544318 2.033016) (xy 2.544318 2.033016) (xy 2.544318 -2.033016) (xy -2.544318 -2.033016)
			)
			(stroke
				(width 0)
				(type default)
			)
			(fill no)
			(layer "F.CrtYd")
		)
		(fp_line
			(start -1.525016 -1.525016)
			(end 1.525016 -1.525016)
			(stroke
				(width 0.1)
				(type default)
			)
			(layer "F.Fab")
		)
		(fp_line
			(start -1.525016 1.525016)
			(end -1.525016 -1.525016)
			(stroke
				(width 0.1)
				(type default)
			)
			(layer "F.Fab")
		)
		(fp_line
			(start 1.525016 -1.525016)
			(end 1.525016 1.525016)
			(stroke
				(width 0.1)
				(type default)
			)
			(layer "F.Fab")
		)
		(fp_line
			(start 1.525016 1.525016)
			(end -1.525016 1.525016)
			(stroke
				(width 0.1)
				(type default)
			)
			(layer "F.Fab")
		)
		(fp_poly
			(pts
				(arc
					(start -2.553462 -1.023112)
					(mid -3.315462 -1.023112)
					(end -2.553462 -1.023112)
				)
			)
			(stroke
				(width 0)
				(type default)
			)
			(fill yes)
			(layer "F.Fab")
		)
		(fp_text user "5"
			(at -2.825496 1.184402 0)
			(unlocked yes)
			(layer "F.SilkS")
			(effects
				(font
					(size 0.635 0.4064)
					(thickness 0.1524)
				)
			)
		)
		(fp_text user "6"
			(at 2.667 1.04775 0)
			(unlocked yes)
			(layer "F.SilkS")
			(effects
				(font
					(size 0.635 0.4064)
					(thickness 0.1524)
				)
			)
		)
		(fp_text user "10"
			(at 2.69875 -0.762 90)
			(unlocked yes)
			(layer "F.SilkS")
			(effects
				(font
					(size 0.635 0.4064)
					(thickness 0.1524)
				)
			)
		)
		(fp_text user "5"
			(at -2.54 1.25095 0)
			(unlocked yes)
			(layer "F.Fab")
			(effects
				(font
					(size 0.635 0.4064)
					(thickness 0.1524)
				)
			)
		)
		(fp_text user "10"
			(at 2.286 -1.67005 0)
			(unlocked yes)
			(layer "F.Fab")
			(effects
				(font
					(size 0.635 0.4064)
					(thickness 0.1524)
				)
			)
		)
		(fp_text user "6"
			(at 2.413 1.37795 0)
			(unlocked yes)
			(layer "F.Fab")
			(effects
				(font
					(size 0.635 0.4064)
					(thickness 0.1524)
				)
			)
		)
		(pad "1" smd circle
			(at -1.515618 -1.000252 180)
			(size 0 0)
			(layers "F.Cu" "F.Mask" "F.Paste")
			(net "XP3R3V_FT4232")
		)
		(pad "2" smd rect
			(at -1.515618 -0.500126)
			(size 1.0414 0.3048)
			(layers "F.Cu" "F.Mask" "F.Paste")
			(net "XP3R3V_FT4232")
		)
		(pad "3" smd rect
			(at -1.515618 0)
			(size 1.0414 0.3048)
			(layers "F.Cu" "F.Mask" "F.Paste")
			(net "UNNAMED_525_ISL80101IRAJZDFN10_")
		)
		(pad "4" smd rect
			(at -1.515618 0.500126)
			(size 1.0414 0.3048)
			(layers "F.Cu" "F.Mask" "F.Paste")
			(net "XP3R3V_FT_PG")
		)
		(pad "5" smd circle
			(at -1.515618 1.000252)
			(size 0 0)
			(layers "F.Cu" "F.Mask" "F.Paste")
			(net "SG")
		)
		(pad "6" smd circle
			(at 1.515618 1.000252)
			(size 0 0)
			(layers "F.Cu" "F.Mask" "F.Paste")
			(net "UNNAMED_525_CAPACITOR_I18_1")
		)
		(pad "7" smd rect
			(at 1.515618 0.500126)
			(size 1.0414 0.3048)
			(layers "F.Cu" "F.Mask" "F.Paste")
			(net "UNNAMED_525_CAPACITOR_I14_1")
		)
		(pad "8" smd rect
			(at 1.515618 0)
			(size 1.0414 0.3048)
			(layers "F.Cu" "F.Mask" "F.Paste")
			(net "Net_788")
		)
		(pad "9" smd rect
			(at 1.515618 -0.500126)
			(size 1.0414 0.3048)
			(layers "F.Cu" "F.Mask" "F.Paste")
			(net "UNNAMED_525_CAPACITOR_I16_1")
		)
		(pad "10" smd circle
			(at 1.515618 -1.000252 180)
			(size 0 0)
			(layers "F.Cu" "F.Mask" "F.Paste")
			(net "UNNAMED_525_CAPACITOR_I16_1")
		)
		(pad "11" smd rect
			(at 0 0)
			(size 1.4478 1.8034)
			(layers "F.Cu" "F.Mask" "F.Paste")
			(net "SG")
		)
	)
	(footprint ""
		(layer "F.Cu")
		(at 85.725 -67.31)
		(property "Reference" "TP18"
			(at -1.2954 -0.85725 0)
			(unlocked yes)
			(layer "F.SilkS")
			(effects
				(font
					(size 0.635 0.4064)
					(thickness 0.1524)
				)
				(justify left)
			)
		)
		(property "Value" ""
			(at 0 0 0)
			(layer "F.Fab")
			(effects
				(font
					(size 1.27 1.27)
				)
			)
		)
		(property "Device Type" "TP_PIONT-TP010CT020B030_PTH-TPA"
			(at -1.341882 0.996696 0)
			(unlocked yes)
			(layer "F.Fab")
			(hide yes)
			(effects
				(font
					(size 0.7874 0.5842)
					(thickness 0.000001)
				)
				(justify left)
			)
		)
		(duplicate_pad_numbers_are_jumpers no)
		(fp_poly
			(pts
				(arc
					(start 0.889 0)
					(mid -0.889 0)
					(end 0.889 0)
				)
			)
			(stroke
				(width 0)
				(type default)
			)
			(fill no)
			(layer "B.CrtYd")
		)
		(fp_poly
			(pts
				(arc
					(start 0.889 0)
					(mid -0.889 0)
					(end 0.889 0)
				)
			)
			(stroke
				(width 0)
				(type default)
			)
			(fill no)
			(layer "F.CrtYd")
		)
		(pad "1" thru_hole circle
			(at 0 0)
			(size 0.508 0.508)
			(drill 0.254)
			(layers "*.Cu" "*.Mask")
			(remove_unused_layers no)
			(net "R_BNO080_BOOT_N")
			(clearance 0.1016)
			(padstack
				(mode front_inner_back)
				(layer "Inner"
					(shape circle)
					(size 0.508 0.508)
					(clearance 0.1016)
				)
				(layer "B.Cu"
					(shape circle)
					(size 0.762 0.762)
					(clearance -0.0254)
				)
			)
		)
	)
)
